(kicad_pcb
	(version 20260206)
	(generator "pcbnew")
	(generator_version "10.0")
	(general
		(thickness 1.6)
		(legacy_teardrops no)
	)
	(paper "A4")
	(title_block
		(title "Bryce Canyon_R.DPB_16317-1_OCP.brd")
		(comment 1 "Bryce Canyon / footprints 519-525 of 2099")
	)
	(layers
		(0 "F.Cu" signal "TOP")
		(4 "In1.Cu" signal "L2GND")
		(6 "In2.Cu" signal "L3")
		(8 "In3.Cu" signal "L4VCC")
		(10 "In4.Cu" signal "L5VCC")
		(12 "In5.Cu" signal "L6")
		(14 "In6.Cu" signal "L7GND")
		(2 "B.Cu" signal "BOTTOM")
		(9 "F.Adhes" user "F.Adhesive")
		(11 "B.Adhes" user "B.Adhesive")
		(13 "F.Paste" user "Package Geometry/Pastemask Top")
		(15 "B.Paste" user "Package Geometry/Pastemask Bottom")
		(5 "F.SilkS" user "Ref Des/Silkscreen Top")
		(7 "B.SilkS" user "Ref Des/Silkscreen Bottom")
		(1 "F.Mask" user "Board Geometry/Soldermask Top")
		(3 "B.Mask" user "Board Geometry/Soldermask Bottom")
		(17 "Dwgs.User" user "User.Drawings")
		(19 "Cmts.User" user "User.Comments")
		(21 "Eco1.User" user "User.Eco1")
		(23 "Eco2.User" user "User.Eco2")
		(25 "Edge.Cuts" user "Board Geometry/Outline")
		(27 "Margin" user)
		(31 "F.CrtYd" user "Package Geometry/Place Bound Top")
		(29 "B.CrtYd" user "Package Geometry/Place Bound Bottom")
		(35 "F.Fab" user "Ref Des/Assembly Top")
		(33 "B.Fab" user "Ref Des/Assembly Bottom")
	)
	(footprint ""
		(layer "F.Cu")
		(at 311.9374 -334.462882)
		(property "Reference" "U20"
			(at 0 0 0)
			(layer "F.SilkS")
			(hide yes)
			(effects
				(font
					(size 1.27 1.27)
				)
			)
		)
		(property "Value" "NCT7368S-GP"
			(at 4.0259 1.5748 0)
			(unlocked yes)
			(layer "F.Fab")
			(hide yes)
			(effects
				(font
					(size 1.016 1.016)
					(thickness 0.1524)
				)
			)
		)
		(property "Device Type" "SOIC8-G3627H69"
			(at 4.0259 0.0508 0)
			(unlocked yes)
			(layer "F.Fab")
			(hide yes)
			(effects
				(font
					(size 1.016 1.016)
					(thickness 0.1524)
				)
			)
		)
		(duplicate_pad_numbers_are_jumpers no)
		(fp_line
			(start -2.8829 -3.6322)
			(end 2.7178 -3.6322)
			(stroke
				(width 0.1524)
				(type default)
			)
			(layer "F.SilkS")
		)
		(fp_line
			(start -2.8829 -0.6223)
			(end -2.2479 0.0127)
			(stroke
				(width 0.1524)
				(type default)
			)
			(layer "F.SilkS")
		)
		(fp_line
			(start -2.8829 0.6477)
			(end -2.8829 -0.6223)
			(stroke
				(width 0.1524)
				(type default)
			)
			(layer "F.SilkS")
		)
		(fp_line
			(start -2.8829 3.6322)
			(end -2.8829 -3.6322)
			(stroke
				(width 0.1524)
				(type default)
			)
			(layer "F.SilkS")
		)
		(fp_line
			(start -2.7051 3.6322)
			(end -2.7051 1.5494)
			(stroke
				(width 0.508)
				(type default)
			)
			(layer "F.SilkS")
		)
		(fp_line
			(start -2.2479 0.0127)
			(end -2.8829 0.6477)
			(stroke
				(width 0.1524)
				(type default)
			)
			(layer "F.SilkS")
		)
		(fp_line
			(start 2.7178 -3.6322)
			(end 2.7178 3.6322)
			(stroke
				(width 0.1524)
				(type default)
			)
			(layer "F.SilkS")
		)
		(fp_line
			(start 2.7178 3.6322)
			(end -2.8829 3.6322)
			(stroke
				(width 0.1524)
				(type default)
			)
			(layer "F.SilkS")
		)
		(fp_poly
			(pts
				(xy -2.1209 2.9972) (xy -2.1209 1.9558) (xy -2.4511 1.9558) (xy -2.4511 -1.9558) (xy -2.1209 -1.9558)
				(xy -2.1209 -2.9972) (xy 2.1209 -2.9972) (xy 2.1209 -1.9558) (xy 2.4511 -1.9558) (xy 2.4511 1.9558)
				(xy 2.1209 1.9558) (xy 2.1209 2.9972)
			)
			(stroke
				(width 0)
				(type default)
			)
			(fill no)
			(layer "F.CrtYd")
		)
		(fp_poly
			(pts
				(xy -2.9591 3.8862) (xy -2.9591 -3.8862) (xy 2.9591 -3.8862) (xy 2.9591 1.95072) (xy 2.4511 1.95072)
				(xy 2.4511 -1.9558) (xy 2.1209 -1.9558) (xy 2.1209 -2.9972) (xy -2.1209 -2.9972) (xy -2.1209 -1.9558)
				(xy -2.4511 -1.9558) (xy -2.4511 1.9558) (xy -2.1209 1.9558) (xy -2.1209 2.9972) (xy 2.1209 2.9972)
				(xy 2.1209 1.9558) (xy 2.9591 1.9558) (xy 2.9591 3.8862)
			)
			(stroke
				(width 0)
				(type default)
			)
			(fill no)
			(layer "F.CrtYd")
		)
		(fp_rect
			(start -2.9591 3.8862)
			(end 2.9591 -3.8862)
			(stroke
				(width 0)
				(type default)
			)
			(fill no)
			(layer "F.Fab")
		)
		(pad "1" smd rect
			(at -1.905 2.5527)
			(size 0.635 1.651)
			(layers "F.Cu" "F.Mask" "F.Paste")
			(net "P3V3_IN")
		)
		(pad "2" smd rect
			(at -0.635 2.5527)
			(size 0.635 1.651)
			(layers "F.Cu" "F.Mask" "F.Paste")
			(net "PWM_SCC_A_ZONE_D")
		)
		(pad "3" smd rect
			(at 0.635 2.5527)
			(size 0.635 1.651)
			(layers "F.Cu" "F.Mask" "F.Paste")
			(net "PWM_BMC_A_ZONE_D")
		)
		(pad "4" smd rect
			(at 1.905 2.5527)
			(size 0.635 1.651)
			(layers "F.Cu" "F.Mask" "F.Paste")
			(net "PWM_BMC_B_ZONE_D")
		)
		(pad "5" smd rect
			(at 1.905 -2.5527)
			(size 0.635 1.651)
			(layers "F.Cu" "F.Mask" "F.Paste")
			(net "PWM_CAMP_SEL2")
		)
		(pad "6" smd rect
			(at 0.635 -2.5527)
			(size 0.635 1.651)
			(layers "F.Cu" "F.Mask" "F.Paste")
			(net "THERMHOT#_D")
		)
		(pad "7" smd rect
			(at -0.635 -2.5527)
			(size 0.635 1.651)
			(layers "F.Cu" "F.Mask" "F.Paste")
			(net "PWM_OUT_D_R")
		)
		(pad "8" smd rect
			(at -1.905 -2.5527)
			(size 0.635 1.651)
			(layers "F.Cu" "F.Mask" "F.Paste")
			(net "PWM_SCC_B_ZONE_D")
		)
		(pad "9" smd rect
			(at 0 0)
			(size 3.6068 2.6924)
			(layers "F.Cu" "F.Mask" "F.Paste")
			(net "GND")
		)
	)
	(footprint ""
		(layer "F.Cu")
		(at 51.7906 -263.779 -90)
		(property "Reference" "C44"
			(at 0 0 270)
			(layer "F.SilkS")
			(hide yes)
			(effects
				(font
					(size 1.27 1.27)
				)
			)
		)
		(property "Value" "SC1U16V3KX-5GP"
			(at 0 -2.8194 270)
			(unlocked yes)
			(layer "F.Fab")
			(hide yes)
			(effects
				(font
					(size 1.016 1.016)
					(thickness 0.1524)
				)
			)
		)
		(property "Device Type" "C603H36"
			(at 0 -4.3434 270)
			(unlocked yes)
			(layer "F.Fab")
			(hide yes)
			(effects
				(font
					(size 1.016 1.016)
					(thickness 0.1524)
				)
			)
		)
		(duplicate_pad_numbers_are_jumpers no)
		(fp_line
			(start 0.508 0)
			(end -0.508 0)
			(stroke
				(width 0.2032)
				(type default)
			)
			(layer "F.SilkS")
		)
		(fp_rect
			(start -0.5842 1.3335)
			(end 0.5842 -1.3335)
			(stroke
				(width 0)
				(type default)
			)
			(fill no)
			(layer "F.CrtYd")
		)
		(fp_rect
			(start -0.5842 1.3335)
			(end 0.5842 -1.3335)
			(stroke
				(width 0)
				(type default)
			)
			(fill no)
			(layer "F.Fab")
		)
		(pad "1" smd custom
			(at 0 -0.762 270)
			(size 0.2159 0.2159)
			(layers "F.Cu" "F.Mask" "F.Paste")
			(net "P5V_HDD1")
			(options
				(clearance outline)
				(anchor circle)
			)
			(primitives
				(gr_poly
					(pts
						(arc
							(start -0.3302 -0.4318)
							(mid -0.402042 -0.402042)
							(end -0.4318 -0.3302)
						)
						(arc
							(start -0.4318 0.3302)
							(mid -0.402042 0.402042)
							(end -0.3302 0.4318)
						)
						(arc
							(start 0.3302 0.4318)
							(mid 0.402042 0.402042)
							(end 0.4318 0.3302)
						)
						(arc
							(start 0.4318 -0.3302)
							(mid 0.402042 -0.402042)
							(end 0.3302 -0.4318)
						)
					)
					(width 0)
					(fill yes)
				)
			)
		)
		(pad "2" smd custom
			(at 0 0.762 270)
			(size 0.2159 0.2159)
			(layers "F.Cu" "F.Mask" "F.Paste")
			(net "GND")
			(options
				(clearance outline)
				(anchor circle)
			)
			(primitives
				(gr_poly
					(pts
						(arc
							(start -0.3302 -0.4318)
							(mid -0.402042 -0.402042)
							(end -0.4318 -0.3302)
						)
						(arc
							(start -0.4318 0.3302)
							(mid -0.402042 0.402042)
							(end -0.3302 0.4318)
						)
						(arc
							(start 0.3302 0.4318)
							(mid 0.402042 0.402042)
							(end 0.4318 0.3302)
						)
						(arc
							(start 0.4318 -0.3302)
							(mid 0.402042 -0.402042)
							(end 0.3302 -0.4318)
						)
					)
					(width 0)
					(fill yes)
				)
			)
		)
	)
	(footprint ""
		(layer "F.Cu")
		(at 458.216 -128.651)
		(property "Reference" "R589"
			(at 0 0 0)
			(layer "F.SilkS")
			(hide yes)
			(effects
				(font
					(size 1.27 1.27)
				)
			)
		)
		(property "Value" "4K7R2F-GP"
			(at 0.064008 -3.993896 0)
			(unlocked yes)
			(layer "F.Fab")
			(hide yes)
			(effects
				(font
					(size 1.016 1.016)
					(thickness 0.1524)
				)
			)
		)
		(property "Device Type" "R402H16"
			(at 0.064008 -5.517896 0)
			(unlocked yes)
			(layer "F.Fab")
			(hide yes)
			(effects
				(font
					(size 1.016 1.016)
					(thickness 0.1524)
				)
			)
		)
		(duplicate_pad_numbers_are_jumpers no)
		(fp_line
			(start -0.508 -0.9398)
			(end -0.508 0.9398)
			(stroke
				(width 0.1524)
				(type default)
			)
			(layer "F.SilkS")
		)
		(fp_line
			(start 0.508 -0.9398)
			(end -0.508 -0.9398)
			(stroke
				(width 0.1524)
				(type default)
			)
			(layer "F.SilkS")
		)
		(fp_rect
			(start -0.508 0.9398)
			(end 0.508 -0.9398)
			(stroke
				(width 0)
				(type default)
			)
			(fill no)
			(layer "F.CrtYd")
		)
		(fp_rect
			(start -0.508 0.9398)
			(end 0.508 -0.9398)
			(stroke
				(width 0)
				(type default)
			)
			(fill no)
			(layer "F.Fab")
		)
		(pad "1" smd custom
			(at 0 -0.4445)
			(size 0.1397 0.1397)
			(layers "F.Cu" "F.Mask" "F.Paste")
			(net "SW_PWR_R_HDD22")
			(options
				(clearance outline)
				(anchor circle)
			)
			(primitives
				(gr_poly
					(pts
						(arc
							(start -0.1778 -0.2794)
							(mid -0.249642 -0.249642)
							(end -0.2794 -0.1778)
						)
						(arc
							(start -0.2794 0.1778)
							(mid -0.249642 0.249642)
							(end -0.1778 0.2794)
						)
						(arc
							(start 0.1778 0.2794)
							(mid 0.249642 0.249642)
							(end 0.2794 0.1778)
						)
						(arc
							(start 0.2794 -0.1778)
							(mid 0.249642 -0.249642)
							(end 0.1778 -0.2794)
						)
					)
					(width 0)
					(fill yes)
				)
			)
		)
		(pad "2" smd custom
			(at 0 0.4445)
			(size 0.1397 0.1397)
			(layers "F.Cu" "F.Mask" "F.Paste")
			(net "GND")
			(options
				(clearance outline)
				(anchor circle)
			)
			(primitives
				(gr_poly
					(pts
						(arc
							(start -0.1778 -0.2794)
							(mid -0.249642 -0.249642)
							(end -0.2794 -0.1778)
						)
						(arc
							(start -0.2794 0.1778)
							(mid -0.249642 0.249642)
							(end -0.1778 0.2794)
						)
						(arc
							(start 0.1778 0.2794)
							(mid 0.249642 0.249642)
							(end 0.2794 0.1778)
						)
						(arc
							(start 0.2794 -0.1778)
							(mid 0.249642 -0.249642)
							(end 0.1778 -0.2794)
						)
					)
					(width 0)
					(fill yes)
				)
			)
		)
	)
	(footprint ""
		(layer "F.Cu")
		(at 167.7162 -369.189 90)
		(property "Reference" "R1060"
			(at 0 0 90)
			(layer "F.SilkS")
			(hide yes)
			(effects
				(font
					(size 1.27 1.27)
				)
			)
		)
		(property "Value" "10R2F-L-GP"
			(at 0.064008 -3.993896 90)
			(unlocked yes)
			(layer "F.Fab")
			(hide yes)
			(effects
				(font
					(size 1.016 1.016)
					(thickness 0.1524)
				)
			)
		)
		(property "Device Type" "R402H14"
			(at 0.064008 -5.517896 90)
			(unlocked yes)
			(layer "F.Fab")
			(hide yes)
			(effects
				(font
					(size 1.016 1.016)
					(thickness 0.1524)
				)
			)
		)
		(duplicate_pad_numbers_are_jumpers no)
		(fp_line
			(start 0.508 -0.9398)
			(end -0.508 -0.9398)
			(stroke
				(width 0.1524)
				(type default)
			)
			(layer "F.SilkS")
		)
		(fp_line
			(start -0.508 -0.9398)
			(end -0.508 0.9398)
			(stroke
				(width 0.1524)
				(type default)
			)
			(layer "F.SilkS")
		)
		(fp_rect
			(start -0.508 0.9398)
			(end 0.508 -0.9398)
			(stroke
				(width 0)
				(type default)
			)
			(fill no)
			(layer "F.CrtYd")
		)
		(fp_rect
			(start -0.508 0.9398)
			(end 0.508 -0.9398)
			(stroke
				(width 0)
				(type default)
			)
			(fill no)
			(layer "F.Fab")
		)
		(pad "1" smd custom
			(at 0 -0.4445 90)
			(size 0.1397 0.1397)
			(layers "F.Cu" "F.Mask" "F.Paste")
			(net "MB0_CM_SENSE_R2_P")
			(options
				(clearance outline)
				(anchor circle)
			)
			(primitives
				(gr_poly
					(pts
						(arc
							(start -0.1778 -0.2794)
							(mid -0.249642 -0.249642)
							(end -0.2794 -0.1778)
						)
						(arc
							(start -0.2794 0.1778)
							(mid -0.249642 0.249642)
							(end -0.1778 0.2794)
						)
						(arc
							(start 0.1778 0.2794)
							(mid 0.249642 0.249642)
							(end 0.2794 0.1778)
						)
						(arc
							(start 0.2794 -0.1778)
							(mid 0.249642 -0.249642)
							(end 0.1778 -0.2794)
						)
					)
					(width 0)
					(fill yes)
				)
			)
		)
		(pad "2" smd custom
			(at 0 0.4445 90)
			(size 0.1397 0.1397)
			(layers "F.Cu" "F.Mask" "F.Paste")
			(net "MB0_HS_SENSE_P")
			(options
				(clearance outline)
				(anchor circle)
			)
			(primitives
				(gr_poly
					(pts
						(arc
							(start -0.1778 -0.2794)
							(mid -0.249642 -0.249642)
							(end -0.2794 -0.1778)
						)
						(arc
							(start -0.2794 0.1778)
							(mid -0.249642 0.249642)
							(end -0.1778 0.2794)
						)
						(arc
							(start 0.1778 0.2794)
							(mid 0.249642 0.249642)
							(end 0.2794 0.1778)
						)
						(arc
							(start 0.2794 -0.1778)
							(mid 0.249642 -0.249642)
							(end 0.1778 -0.2794)
						)
					)
					(width 0)
					(fill yes)
				)
			)
		)
	)
	(footprint ""
		(layer "F.Cu")
		(at 81.407 -214.249)
		(property "Reference" "R237"
			(at 0 0 0)
			(layer "F.SilkS")
			(hide yes)
			(effects
				(font
					(size 1.27 1.27)
				)
			)
		)
		(property "Value" "91R3F-1-GP"
			(at -0.0254 -2.5146 0)
			(unlocked yes)
			(layer "F.Fab")
			(hide yes)
			(effects
				(font
					(size 1.016 1.016)
					(thickness 0.1524)
				)
			)
		)
		(property "Device Type" "R603H22"
			(at -0.0254 -4.0386 0)
			(unlocked yes)
			(layer "F.Fab")
			(hide yes)
			(effects
				(font
					(size 1.016 1.016)
					(thickness 0.1524)
				)
			)
		)
		(duplicate_pad_numbers_are_jumpers no)
		(fp_line
			(start -0.4826 0)
			(end -0.2032 0)
			(stroke
				(width 0.2032)
				(type default)
			)
			(layer "F.SilkS")
		)
		(fp_line
			(start 0.2032 0)
			(end 0.4826 0)
			(stroke
				(width 0.2032)
				(type default)
			)
			(layer "F.SilkS")
		)
		(fp_rect
			(start -0.5842 1.3335)
			(end 0.5842 -1.3335)
			(stroke
				(width 0)
				(type default)
			)
			(fill no)
			(layer "F.CrtYd")
		)
		(fp_rect
			(start -0.5842 1.3335)
			(end 0.5842 -1.3335)
			(stroke
				(width 0)
				(type default)
			)
			(fill no)
			(layer "F.Fab")
		)
		(pad "1" smd custom
			(at 0 -0.762)
			(size 0.2159 0.2159)
			(layers "F.Cu" "F.Mask" "F.Paste")
			(net "P5V_B_1")
			(options
				(clearance outline)
				(anchor circle)
			)
			(primitives
				(gr_poly
					(pts
						(arc
							(start -0.3302 -0.4318)
							(mid -0.402042 -0.402042)
							(end -0.4318 -0.3302)
						)
						(arc
							(start -0.4318 0.3302)
							(mid -0.402042 0.402042)
							(end -0.3302 0.4318)
						)
						(arc
							(start 0.3302 0.4318)
							(mid 0.402042 0.402042)
							(end 0.4318 0.3302)
						)
						(arc
							(start 0.4318 -0.3302)
							(mid 0.402042 -0.402042)
							(end 0.3302 -0.4318)
						)
					)
					(width 0)
					(fill yes)
				)
			)
		)
		(pad "2" smd custom
			(at 0 0.762)
			(size 0.2159 0.2159)
			(layers "F.Cu" "F.Mask" "F.Paste")
			(net "DRV_ACT_2")
			(options
				(clearance outline)
				(anchor circle)
			)
			(primitives
				(gr_poly
					(pts
						(arc
							(start -0.3302 -0.4318)
							(mid -0.402042 -0.402042)
							(end -0.4318 -0.3302)
						)
						(arc
							(start -0.4318 0.3302)
							(mid -0.402042 0.402042)
							(end -0.3302 0.4318)
						)
						(arc
							(start 0.3302 0.4318)
							(mid 0.402042 0.402042)
							(end 0.4318 0.3302)
						)
						(arc
							(start 0.4318 -0.3302)
							(mid 0.402042 -0.402042)
							(end 0.3302 -0.4318)
						)
					)
					(width 0)
					(fill yes)
				)
			)
		)
	)
	(footprint ""
		(layer "F.Cu")
		(at 464.185 -250.444 90)
		(property "Reference" "R330"
			(at 0 0 90)
			(layer "F.SilkS")
			(hide yes)
			(effects
				(font
					(size 1.27 1.27)
				)
			)
		)
		(property "Value" "200KR2F-L-GP"
			(at 0.064008 -3.993896 90)
			(unlocked yes)
			(layer "F.Fab")
			(hide yes)
			(effects
				(font
					(size 1.016 1.016)
					(thickness 0.1524)
				)
			)
		)
		(property "Device Type" "R402H16"
			(at 0.064008 -5.517896 90)
			(unlocked yes)
			(layer "F.Fab")
			(hide yes)
			(effects
				(font
					(size 1.016 1.016)
					(thickness 0.1524)
				)
			)
		)
		(duplicate_pad_numbers_are_jumpers no)
		(fp_line
			(start 0.508 -0.9398)
			(end -0.508 -0.9398)
			(stroke
				(width 0.1524)
				(type default)
			)
			(layer "F.SilkS")
		)
		(fp_line
			(start -0.508 -0.9398)
			(end -0.508 0.9398)
			(stroke
				(width 0.1524)
				(type default)
			)
			(layer "F.SilkS")
		)
		(fp_rect
			(start -0.508 0.9398)
			(end 0.508 -0.9398)
			(stroke
				(width 0)
				(type default)
			)
			(fill no)
			(layer "F.CrtYd")
		)
		(fp_rect
			(start -0.508 0.9398)
			(end 0.508 -0.9398)
			(stroke
				(width 0)
				(type default)
			)
			(fill no)
			(layer "F.Fab")
		)
		(pad "1" smd custom
			(at 0 -0.4445 90)
			(size 0.1397 0.1397)
			(layers "F.Cu" "F.Mask" "F.Paste")
			(net "SW_HDD_R10")
			(options
				(clearance outline)
				(anchor circle)
			)
			(primitives
				(gr_poly
					(pts
						(arc
							(start -0.1778 -0.2794)
							(mid -0.249642 -0.249642)
							(end -0.2794 -0.1778)
						)
						(arc
							(start -0.2794 0.1778)
							(mid -0.249642 0.249642)
							(end -0.1778 0.2794)
						)
						(arc
							(start 0.1778 0.2794)
							(mid 0.249642 0.249642)
							(end 0.2794 0.1778)
						)
						(arc
							(start 0.2794 -0.1778)
							(mid 0.249642 -0.249642)
							(end 0.1778 -0.2794)
						)
					)
					(width 0)
					(fill yes)
				)
			)
		)
		(pad "2" smd custom
			(at 0 0.4445 90)
			(size 0.1397 0.1397)
			(layers "F.Cu" "F.Mask" "F.Paste")
			(net "SW_HDD_N10")
			(options
				(clearance outline)
				(anchor circle)
			)
			(primitives
				(gr_poly
					(pts
						(arc
							(start -0.1778 -0.2794)
							(mid -0.249642 -0.249642)
							(end -0.2794 -0.1778)
						)
						(arc
							(start -0.2794 0.1778)
							(mid -0.249642 0.249642)
							(end -0.1778 0.2794)
						)
						(arc
							(start 0.1778 0.2794)
							(mid 0.249642 0.249642)
							(end 0.2794 0.1778)
						)
						(arc
							(start 0.2794 -0.1778)
							(mid 0.249642 -0.249642)
							(end 0.1778 -0.2794)
						)
					)
					(width 0)
					(fill yes)
				)
			)
		)
	)
	(footprint ""
		(layer "F.Cu")
		(at 478.79 -263.271)
		(property "Reference" "R334"
			(at 0 0 0)
			(layer "F.SilkS")
			(hide yes)
			(effects
				(font
					(size 1.27 1.27)
				)
			)
		)
		(property "Value" "2R6F-GP"
			(at -0.0508 -4.8514 0)
			(unlocked yes)
			(layer "F.Fab")
			(hide yes)
			(effects
				(font
					(size 1.016 1.016)
					(thickness 0.1524)
				)
			)
		)
		(property "Device Type" "R1206H26"
			(at 0 -6.3754 0)
			(unlocked yes)
			(layer "F.Fab")
			(hide yes)
			(effects
				(font
					(size 1.016 1.016)
					(thickness 0.1524)
				)
			)
		)
		(duplicate_pad_numbers_are_jumpers no)
		(fp_line
			(start -1.016 -2.2352)
			(end 1.016 -2.2352)
			(stroke
				(width 0.1524)
				(type default)
			)
			(layer "F.SilkS")
		)
		(fp_line
			(start -1.016 2.2352)
			(end -1.016 -2.2352)
			(stroke
				(width 0.1524)
				(type default)
			)
			(layer "F.SilkS")
		)
		(fp_line
			(start 1.016 -2.2352)
			(end 1.016 2.2352)
			(stroke
				(width 0.1524)
				(type default)
			)
			(layer "F.SilkS")
		)
		(fp_line
			(start 1.016 2.2352)
			(end -1.016 2.2352)
			(stroke
				(width 0.1524)
				(type default)
			)
			(layer "F.SilkS")
		)
		(fp_rect
			(start -1.0922 2.3114)
			(end 1.0922 -2.3114)
			(stroke
				(width 0)
				(type default)
			)
			(fill no)
			(layer "F.CrtYd")
		)
		(fp_poly
			(pts
				(xy -1.0922 -2.3114) (xy 1.0922 -2.3114) (xy 1.0922 2.3114) (xy -1.0922 2.3114)
			)
			(stroke
				(width 0)
				(type default)
			)
			(fill no)
			(layer "F.Fab")
		)
		(pad "1" smd rect
			(at 0 -1.397)
			(size 1.651 1.27)
			(layers "F.Cu" "F.Mask" "F.Paste")
			(net "P5V_HDD11")
		)
		(pad "2" smd rect
			(at 0 1.397)
			(size 1.651 1.27)
			(layers "F.Cu" "F.Mask" "F.Paste")
			(net "5V_PRE_11")
		)
	)
)
